;LEADER: 12 
;HEADER: none 
;CODE  : ASCII 
;FILE  : C:/<user>/cadence/projects_wcs/tbp_e1020/X887571-005_TBP/worklib/wcs2tbp/physical/gerber/bottom_probe.drl for bottom probe holes 
G90
X-129878Y-005220
X-129870Y-003570
X-165600Y-013500
X-129800Y-004120
X-129626Y-017504
X-147506Y-002216
X-111549Y-010424
X-057750Y-011500
X-093250Y-000750
X-003450Y-008350
X-074591Y-017307
X-074591Y-016756
X-074591Y-015654
X-074591Y-013449
X-038650Y-000550
Y-005650
X-038524Y-015735
X-110000Y-001500
X-109628Y-017065
X-073803Y-012307
X-073803Y-012858
X-073803Y-013961
X-073803Y-014512
X-073803Y-015614
X-073803Y-016165
X-073803Y-017268
X-073803Y-017819
X-109560Y-017960
X-145000Y-011250
X-037400Y-003150
X-073016Y-010142
X-073016Y-010693
X-073016Y-011795
X-073016Y-012346
X-073016Y-015102
X-073016Y-015654
X-073016Y-016756
X-073016Y-017307
X-019100Y-005640
X-019030Y-000420
Y-002890
X-000950Y-005850
X-072228Y-017819
X-072228Y-017268
X-072228Y-016165
X-072228Y-015614
X-072228Y-014512
X-072228Y-013961
X-072228Y-012858
X-072228Y-012307
X-072228Y-011205
X-072228Y-010654
X-143750Y-017500
X-161598Y-017307
X-161598Y-016756
X-161598Y-015654
X-161598Y-012898
X-125532Y-015735
X-017980Y-004350
X-071441Y-017307
X-071441Y-016756
X-071441Y-015654
X-071441Y-015102
X-071441Y-014000
X-071441Y-013449
X-071441Y-012346
X-071441Y-011795
X-071441Y-010693
X-071441Y-010142
X-160811Y-012307
X-160811Y-012858
X-160811Y-013961
X-160811Y-014512
X-160811Y-015614
X-160811Y-016165
X-160811Y-017268
X-160811Y-017819
X-017635Y-002720
X000300Y-009600
X-017510Y-000180
X-070654Y-010654
X-070654Y-011205
X-070654Y-012307
X-070654Y-012858
X-070654Y-013961
X-070654Y-014512
X-070654Y-015614
X-070654Y-016165
X-070654Y-017268
X-070654Y-017819
X-034800Y-003150
X-160024Y-010142
X-160024Y-010693
X-160024Y-011795
X-160024Y-012346
X-160024Y-013449
X-160024Y-015102
X-160024Y-015654
X-160024Y-016756
X-160024Y-017307
X-142125Y-008125
X-034744Y-015735
X-034240Y-008750
X-105690Y-005630
X-069866Y-017307
X-069866Y-016756
X-069866Y-015654
X-069866Y-015102
X-069866Y-014000
X-069866Y-013449
X-069866Y-012346
X-069866Y-011795
X-069866Y-010693
X-069866Y-010142
X-159236Y-017819
X-159236Y-017268
X-159236Y-016165
X-159236Y-015614
X-159236Y-014512
X-159236Y-013961
X-159236Y-012858
X-159236Y-012307
X-159236Y-011205
X-159236Y-010654
X-105490Y-002980
X-105460Y-000510
X-123250Y-004500
X-105120Y-004410
X-069079Y-017819
X-069079Y-017268
X-069079Y-016165
X-069079Y-015614
X-069079Y-014512
X-069079Y-013961
X-069079Y-012858
X-069079Y-012307
X-069079Y-011205
X-069079Y-010654
X-158449Y-017307
X-158449Y-016756
X-158449Y-015654
X-158449Y-015102
X-158449Y-014000
X-158449Y-013449
X-158449Y-012346
X-158449Y-011795
X-158449Y-010693
X-158449Y-010142
X-104730Y-000270
X-104729Y-002630
X-068500Y-004500
X-032693Y-017346
X-032693Y-016795
X-032693Y-015693
X-032693Y-015142
X-032693Y-014039
X-032693Y-013488
X-068291Y-010142
X-068291Y-010693
X-068291Y-011795
X-068291Y-012346
X-068291Y-013449
X-068291Y-014000
X-068291Y-015102
X-068291Y-015654
X-068291Y-016756
X-068291Y-017307
X-157661Y-010654
X-157661Y-011205
X-157661Y-012307
X-157661Y-012858
X-157661Y-013961
X-157661Y-014512
X-157661Y-015614
X-157661Y-016165
X-157661Y-017268
X-157661Y-017819
X-050250Y-001250
X-014441Y-017346
X-014441Y-016795
X-014441Y-015693
X-014441Y-015142
X-014441Y-013488
X-014441Y-012937
X-086000Y-004500
X-121752Y-015735
X-032150Y-004750
X-031906Y-013449
X-031906Y-014000
X-031906Y-015654
X-031906Y-017307
X-031906Y-017858
X-013917Y-006866
X-067504Y-010654
X-067504Y-011205
X-067504Y-012307
X-067504Y-012858
X-067504Y-013961
X-067504Y-014512
X-067504Y-015614
X-067504Y-016165
X-067504Y-017268
X-067504Y-017819
X-156874Y-017307
X-156874Y-016756
X-156874Y-015654
X-156874Y-015102
X-156874Y-014000
X-156874Y-013449
X-156874Y-012346
X-156874Y-011795
X-156874Y-010693
X-156874Y-010142
X-013654Y-014000
X-013654Y-014551
X-013654Y-015654
X-013654Y-016205
X-013654Y-017858
X-138750Y-015000
X-013327Y-007811
X-031118Y-017346
X-031118Y-016795
X-031118Y-015693
X-031118Y-015142
X-031118Y-014591
X-031118Y-014039
X-031118Y-013488
X-156087Y-017819
X-156087Y-017268
X-156087Y-016165
X-156087Y-015614
X-156087Y-014512
X-156087Y-013961
X-156087Y-012858
X-156087Y-012307
X-156087Y-011205
X-156087Y-010654
X-012866Y-017346
X-012866Y-016795
X-012866Y-015693
X-012866Y-015142
X-012866Y-014039
X-012866Y-013488
X-012650Y-000850
X-030331Y-017858
X-030331Y-017307
X-030331Y-016205
X-030331Y-015654
X-030331Y-015102
X-030331Y-014551
X-030331Y-014000
X-030250Y-001520
X-119701Y-017346
X-119701Y-016795
X-119701Y-015693
X-119701Y-015142
X-119701Y-014039
X-119701Y-013488
X-155299Y-010142
X-155299Y-010693
X-155299Y-011795
X-155299Y-012346
X-155299Y-013449
X-155299Y-014000
X-155299Y-015102
X-155299Y-015654
X-155299Y-016756
X-155299Y-017307
X-101449Y-017346
X-101449Y-016795
X-101449Y-015693
X-101449Y-015142
X-101449Y-014039
X-101449Y-013488
X-137125Y-011250
X-101250Y-000750
X-119100Y-004650
X-029543Y-013488
X-029543Y-015142
X-029543Y-016795
X-029543Y-017346
X-136875Y-008250
X-118913Y-013449
X-118913Y-014000
X-118913Y-017307
X-118913Y-017858
X-154512Y-010654
X-154512Y-011205
X-154512Y-012307
X-154512Y-012858
X-154512Y-013961
X-154512Y-014512
X-154512Y-015614
X-154512Y-016165
X-154512Y-017268
X-154512Y-017819
X-011291Y-013488
X-011291Y-014039
X-011291Y-015142
X-011291Y-015693
X-011291Y-016795
X-011291Y-017346
X-029080Y-002600
X-100661Y-014000
X-100661Y-014551
X-100661Y-015654
X-100661Y-016205
X-100661Y-017307
X-100661Y-017858
X-028950Y-003250
X-028756Y-014000
X-028756Y-014551
X-028756Y-015654
X-028756Y-016205
X-028756Y-017307
X-028756Y-017858
X-118126Y-013488
X-118126Y-014039
X-118126Y-015142
X-118126Y-015693
X-118126Y-016795
X-118126Y-017346
X-117895Y-002325
X-010504Y-014551
X-010504Y-015654
X-010504Y-016205
X-010504Y-017307
X-010504Y-017858
X-099874Y-017346
X-099874Y-016795
X-099874Y-015693
X-099874Y-015142
X-099874Y-014039
X-099874Y-013488
X-153506Y-002216
X-153500Y-003250
X-117339Y-017858
X-117339Y-017307
X-117339Y-016205
X-117339Y-015654
X-117339Y-015102
X-117339Y-013449
X-009882Y-004819
X-009882Y-007811
X-099087Y-017858
X-099087Y-017307
X-099087Y-016205
X-099087Y-015654
X-099087Y-014551
X-099087Y-014000
X-009587Y-008362
Y-005370
X-152436Y-012536
X-116551Y-013488
X-116551Y-015142
X-116551Y-016795
X-116551Y-017346
X-062696Y-016939
X-008996Y-007811
X-026800Y-000050
X-098299Y-013488
X-098299Y-014039
X-098299Y-015142
X-098299Y-015693
X-098299Y-016795
X-098299Y-017346
X-044444Y-008071
X-116015Y-002675
X-115970Y-000575
X-115870Y-001625
X-044280Y-004660
X-062161Y-007689
X-115764Y-014000
X-115764Y-014551
X-115764Y-015654
X-115764Y-016205
X-115764Y-017307
X-115764Y-017858
X-133540Y-007500
X-097512Y-014000
X-097512Y-014551
X-097512Y-015654
X-097512Y-016205
X-097512Y-017307
X-097512Y-017858
X-025873Y-010417
X-115150Y-001500
X-025550Y-002550
X-025480Y-018000
X-097000Y-000750
X-025179Y-010433
X-043040Y-003560
X-043018Y-005210
X-132484Y-008212
X-132450Y-002696
X-042940Y-004110
X-042450Y-002650
X-024541Y-010424
X-149704Y-016939
X-005950Y-002100
Y-005850
Y-010850
X-131120Y-003020
X-112881Y-010417
X-148669Y-007689
X-023287Y-010420
X-023050Y-000050
X-112490Y-017065
X-112470Y-018000
X-112187Y-010433
X-022620Y-017065
X-022540Y-017980
M30
